# Kintex 410T devboard — KiCad custom design rules (.kicad_dru)
(version 1)

(rule "DDR_40OHM_SE_outer" 
	(constraint track_width (opt 0.256mm))
	(constraint clearance (opt 0.1mm))
	(condition "(A.NetClass == '40Ohm-se_DQ')")
	(layer outer)
)

(rule "DDR_40OHM_SE_inner" 
	(constraint track_width (opt 0.157mm))
	(constraint clearance (opt 0.1mm))
	(condition "(A.NetClass == '40Ohm-se_DQ')")
	(layer inner)
)

#calculated as 80Ohm diff @ 44OHM SE 
(rule "DDR_80OHM_diff_outer" 
	(constraint track_width (opt 0.225mm))
	(constraint diff_pair_gap (opt 0.205mm))
	(constraint clearance (opt 0.1mm))
	(condition "(A.NetClass == '80Ohm-diff_DQS') ")
	(layer outer)
)

#calculated as 80Ohm diff @ 42,5OHM SE 
(rule "DDR_80OHM_diff_inner" 
	(constraint track_width (opt 0.141mm))
	(constraint diff_pair_gap (opt 0.165mm))
	(constraint clearance (opt 0.1mm))
	(condition "(A.NetClass == '80Ohm-diff_DQS') ")
	(layer inner)
)

(rule "50OHM_SE_outer" 
	(constraint track_width (opt 0.184mm))
	(constraint clearance (opt 0.1mm))
	(condition "(A.NetClass == '50Ohm-se')")
	(layer outer)
)

(rule "50OHM_SE_inner" 
	(constraint track_width (opt 0.1mm))
	(constraint clearance (opt 0.1mm))
	(condition "(A.NetClass == '50Ohm-se')")
	(layer inner)
)

#calculated as 100Ohm diff @ 55OHM SE 
(rule "100OHM_diff_outer" 
	(constraint track_width (opt 0.153mm))
	(constraint diff_pair_gap (opt 0.208mm))
	(constraint clearance (opt 0.1mm))
	(condition "(A.NetClass == '100Ohm-diff') && !A.insideCourtyard('U1')")
	(layer outer)
)

(rule "100OHM_diff_inner" 
	(constraint track_width (opt 0.1mm))
	(constraint diff_pair_gap (opt 0.25mm))
	(constraint clearance (opt 0.1mm))
	(condition "(A.NetClass == '100Ohm-diff') && !A.insideCourtyard('U1')")
	(layer inner)
)

#104Ohm for outer - avoid!, 90Ohm for inner 
(rule "diff_BGA_fanout" 
	(constraint track_width (opt 0.1mm))
	(constraint diff_pair_gap (opt 0.1mm))
	(constraint clearance (opt 0.1mm))
	(condition "((A.NetClass == '90Ohm-diff')||(A.NetClass == '100Ohm-diff')||(A.NetClass == '85Ohm-diff_PCIe')) && A.insideCourtyard('U1')")
)

#calculated as 90Ohm diff @ 47,5OHM SE 
(rule "9OHM_diff_outer" 
	(constraint track_width (opt 0.198mm))
	(constraint diff_pair_gap (opt 0.277mm))
	(constraint clearance (opt 0.1mm))
	(condition "(A.NetClass == '90Ohm-diff') && !A.insideCourtyard('U1')")
	(layer outer)
)

#calculated as 90Ohm diff @ 47,5OHM SE 
(rule "90OHM_diff_inner" 
	(constraint track_width (opt 0.114mm))
	(constraint diff_pair_gap (opt 0.173mm))
	(constraint clearance (opt 0.1mm))
	(condition "(A.NetClass == '90Ohm-diff') && !A.insideCourtyard('U1')")
	(layer inner)
)

#calculated as 90Ohm diff @ 47,5OHM SE 
(rule "90OHM_diff_inner" 
	(constraint track_width (opt 0.1mm))
	(constraint diff_pair_gap (opt 0.1mm))
	(constraint clearance (opt 0.1mm))
	(condition "(A.NetClass == '90Ohm-diff') && A.insideCourtyard('U1')")
	(layer inner)
)

#calculated as 85Ohm diff @ 47OHM SE 
(rule "85OHM_diff_outer" 
	(constraint track_width (opt 0.201mm))
	(constraint diff_pair_gap (opt 0.2mm))
	(constraint clearance (opt 0.1mm))
	(condition "(A.NetClass == '85Ohm-diff_PCIe') && !A.insideCourtyard('U1')")
	(layer outer)
)

#calculated as 85Ohm diff @ 45OHM SE 
(rule "85OHM_diff_inner" 
	(constraint track_width (opt 0.127mm))
	(constraint diff_pair_gap (opt 0.17mm))
	(constraint clearance (opt 0.1mm))
	(condition "(A.NetClass == '85Ohm-diff_PCIe')")
	(layer inner)
)

#calculated as 85Ohm diff @ 53.6OHM SE 
(rule "85OHM_diff_FMC_fanout_outer" 
	(constraint track_width (opt 0.16mm))
	(constraint diff_pair_gap (opt 0.104mm))
	(constraint clearance (opt 0.1mm))
	(condition "((A.NetClass == '85Ohm-diff_PCIe')) && A.insideCourtyard('J18')")
	(layer outer)
)


